(kicad_pcb
	(version 20240108)
	(generator "pcbnew")
	(generator_version "8.0")
	(general
		(thickness 1.62)
		(legacy_teardrops no)
	)
	(paper "A4")
	(title_block
		(title "Jetson Orin Baseboard")
		(date "2025-03-12")
		(rev "1.3.4")
		(company "Antmicro Ltd")
		(comment 1 "www.antmicro.com")
		(comment 9 "footprints 272-272 of 677")
	)
	(layers
		(0 "F.Cu" signal)
		(1 "In1.Cu" signal)
		(2 "In2.Cu" signal)
		(3 "In3.Cu" signal)
		(4 "In4.Cu" jumper)
		(5 "In5.Cu" signal)
		(6 "In6.Cu" signal)
		(31 "B.Cu" signal)
		(32 "B.Adhes" user "B.Adhesive")
		(33 "F.Adhes" user "F.Adhesive")
		(34 "B.Paste" user)
		(35 "F.Paste" user)
		(36 "B.SilkS" user "B.Silkscreen")
		(37 "F.SilkS" user "F.Silkscreen")
		(38 "B.Mask" user)
		(39 "F.Mask" user)
		(40 "Dwgs.User" user "User.Drawings")
		(41 "Cmts.User" user "User.Comments")
		(42 "Eco1.User" user "User.Eco1")
		(43 "Eco2.User" user "User.Eco2")
		(44 "Edge.Cuts" user)
		(45 "Margin" user)
		(46 "B.CrtYd" user "B.Courtyard")
		(47 "F.CrtYd" user "F.Courtyard")
		(48 "B.Fab" user)
		(49 "F.Fab" user)
	)
	(footprint "antmicro-footprints:Bus_M.2_Socket_Key_E_TE_2199230-6"
		(locked yes)
		(layer "F.Cu")
		(at 120.73 95.12 -90)
		(property "Reference" "J1"
			(at -2 -1.2 90)
			(layer "F.SilkS")
			(effects
				(font
					(size 0.7 0.7)
					(thickness 0.15)
				)
				(justify right bottom)
			)
		)
		(property "Value" "Bus_M.2_2199230-6"
			(at -1.75 9.5 90)
			(layer "F.Fab")
			(effects
				(font
					(size 0.7 0.7)
					(thickness 0.15)
				)
				(justify right bottom)
			)
		)
		(property "Footprint" "antmicro-footprints:Bus_M.2_Socket_Key_E_TE_2199230-6"
			(at 0 0 -90)
			(layer "F.Fab")
			(hide yes)
			(effects
				(font
					(size 1.27 1.27)
					(thickness 0.15)
				)
			)
		)
		(property "Datasheet" "https://www.te.com/usa-en/product-2199230-6.datasheet.pdf"
			(at 0 0 -90)
			(layer "F.Fab")
			(hide yes)
			(effects
				(font
					(size 1.27 1.27)
					(thickness 0.15)
				)
			)
		)
		(property "Author" "Antmicro"
			(at 25.61 215.85 0)
			(layer "F.Fab")
			(hide yes)
			(effects
				(font
					(size 1 1)
					(thickness 0.15)
				)
			)
		)
		(property "License" "Apache-2.0"
			(at 25.61 215.85 0)
			(layer "F.Fab")
			(hide yes)
			(effects
				(font
					(size 1 1)
					(thickness 0.15)
				)
			)
		)
		(property "MPN" "2199230-6 "
			(at 25.61 215.85 0)
			(layer "F.Fab")
			(hide yes)
			(effects
				(font
					(size 1 1)
					(thickness 0.15)
				)
			)
		)
		(property "Manufacturer" "TE Connectivity"
			(at 25.61 215.85 0)
			(layer "F.Fab")
			(hide yes)
			(effects
				(font
					(size 1 1)
					(thickness 0.15)
				)
			)
		)
		(sheetname "M.2")
		(sheetfile "m-2.kicad_sch")
		(attr smd)
		(fp_line
			(start -9.599 4.1)
			(end -9.249 4.1)
			(stroke
				(width 0.15)
				(type solid)
			)
			(layer "F.SilkS")
		)
		(fp_line
			(start -3.75 4.1)
			(end -1.75 4.1)
			(stroke
				(width 0.15)
				(type solid)
			)
			(layer "F.SilkS")
		)
		(fp_line
			(start 9.251 4.1)
			(end 9.601 4.1)
			(stroke
				(width 0.15)
				(type solid)
			)
			(layer "F.SilkS")
		)
		(fp_line
			(start 9.601 4.1)
			(end 9.601 2.85)
			(stroke
				(width 0.15)
				(type solid)
			)
			(layer "F.SilkS")
		)
		(fp_line
			(start -10.999 2.85)
			(end -10.999 -1.5)
			(stroke
				(width 0.15)
				(type solid)
			)
			(layer "F.SilkS")
		)
		(fp_line
			(start -9.599 2.85)
			(end -9.599 4.1)
			(stroke
				(width 0.15)
				(type solid)
			)
			(layer "F.SilkS")
		)
		(fp_line
			(start -9.599 2.85)
			(end -10.999 2.85)
			(stroke
				(width 0.15)
				(type solid)
			)
			(layer "F.SilkS")
		)
		(fp_line
			(start 10.999 2.85)
			(end 9.601 2.85)
			(stroke
				(width 0.15)
				(type solid)
			)
			(layer "F.SilkS")
		)
		(fp_line
			(start 10.999 -1.5)
			(end 10.999 2.85)
			(stroke
				(width 0.15)
				(type solid)
			)
			(layer "F.SilkS")
		)
		(fp_line
			(start -3.499 -3.899)
			(end -1.499 -3.899)
			(stroke
				(width 0.15)
				(type solid)
			)
			(layer "F.SilkS")
		)
		(fp_circle
			(center -9.249 -5.64)
			(end -9.199 -5.64)
			(stroke
				(width 0.15)
				(type solid)
			)
			(fill solid)
			(layer "F.SilkS")
		)
		(fp_rect
			(start -11.94 -5.34)
			(end 11.95 5.35)
			(stroke
				(width 0.05)
				(type solid)
			)
			(fill none)
			(layer "F.CrtYd")
		)
		(fp_line
			(start -9.999 -0.25)
			(end 9.999 -0.25)
			(stroke
				(width 0.15)
				(type solid)
			)
			(layer "F.Fab")
		)
		(fp_text user "${REFERENCE}"
			(at -1.8 10.8 90)
			(layer "F.Fab")
			(hide yes)
			(effects
				(font
					(size 0.7 0.7)
					(thickness 0.15)
				)
				(justify right bottom)
			)
		)
		(fp_text user "License: Apache-2.0"
			(at -1.8 13.55 90)
			(layer "F.Fab")
			(hide yes)
			(effects
				(font
					(size 0.7 0.7)
					(thickness 0.15)
				)
				(justify right bottom)
			)
		)
		(fp_text user "Author: Antmicro"
			(at -1.8 12.1 90)
			(layer "F.Fab")
			(hide yes)
			(effects
				(font
					(size 0.7 0.7)
					(thickness 0.15)
				)
				(justify right bottom)
			)
		)
		(pad "" np_thru_hole circle
			(at -9.999 1.499 270)
			(size 1.1 1.1)
			(drill 1.1)
			(layers "*.Cu" "*.Mask")
		)
		(pad "" np_thru_hole circle
			(at 9.999 1.499 270)
			(size 1.6 1.6)
			(drill 1.6)
			(layers "*.Cu" "*.Mask")
		)
		(pad "1" smd rect
			(at -9.249 -3.749 270)
			(size 0.3 1.55)
			(layers "F.Cu" "F.Paste" "F.Mask")
			(net 1 "GND")
			(pinfunction "GND")
			(pintype "power_in")
		)
		(pad "2" smd rect
			(at -9.001 3.749 270)
			(size 0.3 1.55)
			(layers "F.Cu" "F.Paste" "F.Mask")
			(net 87 "+3V3")
			(pinfunction "3.3V")
			(pintype "power_in")
		)
		(pad "3" smd rect
			(at -8.751 -3.749 270)
			(size 0.3 1.55)
			(layers "F.Cu" "F.Paste" "F.Mask")
			(net 616 "/M.2/USB_E_P")
			(pinfunction "USB_D_P")
			(pintype "bidirectional")
		)
		(pad "4" smd rect
			(at -8.501 3.749 270)
			(size 0.3 1.55)
			(layers "F.Cu" "F.Paste" "F.Mask")
			(net 87 "+3V3")
			(pinfunction "3.3V")
			(pintype "passive")
		)
		(pad "5" smd rect
			(at -8.251 -3.749 270)
			(size 0.3 1.55)
			(layers "F.Cu" "F.Paste" "F.Mask")
			(net 617 "/M.2/USB_E_N")
			(pinfunction "USB_D_N")
			(pintype "bidirectional")
		)
		(pad "6" smd rect
			(at -8 3.749 270)
			(size 0.3 1.55)
			(layers "F.Cu" "F.Paste" "F.Mask")
			(net 169 "/M.2/~{LED1}")
			(pinfunction "~{LED_1}")
			(pintype "output")
		)
		(pad "7" smd rect
			(at -7.75 -3.749 270)
			(size 0.3 1.55)
			(layers "F.Cu" "F.Paste" "F.Mask")
			(net 1 "GND")
			(pinfunction "GND")
			(pintype "passive")
		)
		(pad "8" smd rect
			(at -7.5 3.749 270)
			(size 0.3 1.55)
			(layers "F.Cu" "F.Paste" "F.Mask")
			(net 170 "/M.2/M2_E_PCM_CLK")
			(pinfunction "PCM_CLK")
			(pintype "bidirectional")
		)
		(pad "9" smd rect
			(at -7.25 -3.749 270)
			(size 0.3 1.55)
			(layers "F.Cu" "F.Paste" "F.Mask")
			(net 190 "unconnected-(J1-SDIO_CLK-Pad9)")
			(pinfunction "SDIO_CLK")
			(pintype "input+no_connect")
		)
		(pad "10" smd rect
			(at -7 3.749 270)
			(size 0.3 1.55)
			(layers "F.Cu" "F.Paste" "F.Mask")
			(net 176 "/M.2/M2_E_PCM_SYNC")
			(pinfunction "PCM_SYNC")
			(pintype "bidirectional")
		)
		(pad "11" smd rect
			(at -6.75 -3.749 270)
			(size 0.3 1.55)
			(layers "F.Cu" "F.Paste" "F.Mask")
			(net 191 "unconnected-(J1-SDIO_CMD-Pad11)")
			(pinfunction "SDIO_CMD")
			(pintype "bidirectional+no_connect")
		)
		(pad "12" smd rect
			(at -6.5 3.749 270)
			(size 0.3 1.55)
			(layers "F.Cu" "F.Paste" "F.Mask")
			(net 651 "/M.2/M2_E_PCM_IN")
			(pinfunction "PCM_IN")
			(pintype "bidirectional")
		)
		(pad "13" smd rect
			(at -6.25 -3.749 270)
			(size 0.3 1.55)
			(layers "F.Cu" "F.Paste" "F.Mask")
			(net 202 "unconnected-(J1-SDIO_D0-Pad13)")
			(pinfunction "SDIO_D0")
			(pintype "bidirectional+no_connect")
		)
		(pad "14" smd rect
			(at -6 3.749 270)
			(size 0.3 1.55)
			(layers "F.Cu" "F.Paste" "F.Mask")
			(net 178 "/M.2/M2_E_PCM_OUT")
			(pinfunction "PCM_OUT")
			(pintype "bidirectional")
		)
		(pad "15" smd rect
			(at -5.75 -3.749 270)
			(size 0.3 1.55)
			(layers "F.Cu" "F.Paste" "F.Mask")
			(net 203 "unconnected-(J1-SDIO_D1-Pad15)")
			(pinfunction "SDIO_D1")
			(pintype "bidirectional+no_connect")
		)
		(pad "16" smd rect
			(at -5.5 3.749 270)
			(size 0.3 1.55)
			(layers "F.Cu" "F.Paste" "F.Mask")
			(net 652 "/M.2/~{LED2}")
			(pinfunction "~{LED_2}")
			(pintype "output")
		)
		(pad "17" smd rect
			(at -5.25 -3.749 270)
			(size 0.3 1.55)
			(layers "F.Cu" "F.Paste" "F.Mask")
			(net 208 "unconnected-(J1-SDIO_D2-Pad17)")
			(pinfunction "SDIO_D2")
			(pintype "bidirectional+no_connect")
		)
		(pad "18" smd rect
			(at -5.001 3.749 270)
			(size 0.3 1.55)
			(layers "F.Cu" "F.Paste" "F.Mask")
			(net 1 "GND")
			(pinfunction "GND")
			(pintype "passive")
		)
		(pad "19" smd rect
			(at -4.751 -3.749 270)
			(size 0.3 1.55)
			(layers "F.Cu" "F.Paste" "F.Mask")
			(net 209 "unconnected-(J1-SDIO_D3-Pad19)")
			(pinfunction "SDIO_D3")
			(pintype "bidirectional+no_connect")
		)
		(pad "20" smd rect
			(at -4.501 3.749 270)
			(size 0.3 1.55)
			(layers "F.Cu" "F.Paste" "F.Mask")
			(net 183 "/M.2/~{M2_E_UART_WAKE}")
			(pinfunction "~{UART_WAKE}")
			(pintype "output")
		)
		(pad "21" smd rect
			(at -4.251 -3.749 270)
			(size 0.3 1.55)
			(layers "F.Cu" "F.Paste" "F.Mask")
			(net 210 "unconnected-(J1-SDIO_~{WAKE}-Pad21)")
			(pinfunction "SDIO_~{WAKE}")
			(pintype "bidirectional+no_connect")
		)
		(pad "22" smd rect
			(at -4.001 3.749 270)
			(size 0.3 1.55)
			(layers "F.Cu" "F.Paste" "F.Mask")
			(net 192 "/M.2/M2_E_UART_RX")
			(pinfunction "UART_RXD")
			(pintype "bidirectional")
		)
		(pad "23" smd rect
			(at -3.75 -3.749 270)
			(size 0.3 1.55)
			(layers "F.Cu" "F.Paste" "F.Mask")
			(net 211 "unconnected-(J1-SDIO_~{RESET}-Pad23)")
			(pinfunction "SDIO_~{RESET}")
			(pintype "input+no_connect")
		)
		(pad "32" smd rect
			(at -1.5 3.749 270)
			(size 0.3 1.55)
			(layers "F.Cu" "F.Paste" "F.Mask")
			(net 188 "/M.2/M2_E_UART_TX")
			(pinfunction "UART_TXD")
			(pintype "bidirectional")
		)
		(pad "33" smd rect
			(at -1.25 -3.749 270)
			(size 0.3 1.55)
			(layers "F.Cu" "F.Paste" "F.Mask")
			(net 1 "GND")
			(pinfunction "GND")
			(pintype "passive")
		)
		(pad "34" smd rect
			(at -1 3.749 270)
			(size 0.3 1.55)
			(layers "F.Cu" "F.Paste" "F.Mask")
			(net 199 "/M.2/M2_E_UART_CTS")
			(pinfunction "UART_CTS")
			(pintype "bidirectional")
		)
		(pad "35" smd rect
			(at -0.75 -3.749 270)
			(size 0.3 1.55)
			(layers "F.Cu" "F.Paste" "F.Mask")
			(net 96 "/M.2/C_PCIE1_TX0_P")
			(pinfunction "PET0_P")
			(pintype "input")
		)
		(pad "36" smd rect
			(at -0.5 3.749 270)
			(size 0.3 1.55)
			(layers "F.Cu" "F.Paste" "F.Mask")
			(net 195 "/M.2/M2_E_UART_RTS")
			(pinfunction "UART_RTS")
			(pintype "bidirectional")
		)
		(pad "37" smd rect
			(at -0.25 -3.749 270)
			(size 0.3 1.55)
			(layers "F.Cu" "F.Paste" "F.Mask")
			(net 97 "/M.2/C_PCIE1_TX0_N")
			(pinfunction "PET0_N")
			(pintype "input")
		)
		(pad "38" smd rect
			(at 0 3.749 270)
			(size 0.3 1.55)
			(layers "F.Cu" "F.Paste" "F.Mask")
			(net 222 "unconnected-(J1-VENDOR_1-Pad38)")
			(pinfunction "VENDOR_1")
			(pintype "bidirectional+no_connect")
		)
		(pad "39" smd rect
			(at 0.25 -3.749 270)
			(size 0.3 1.55)
			(layers "F.Cu" "F.Paste" "F.Mask")
			(net 1 "GND")
			(pinfunction "GND")
			(pintype "passive")
		)
		(pad "40" smd rect
			(at 0.5 3.749 270)
			(size 0.3 1.55)
			(layers "F.Cu" "F.Paste" "F.Mask")
			(net 224 "unconnected-(J1-VENDOR_2-Pad40)")
			(pinfunction "VENDOR_2")
			(pintype "bidirectional+no_connect")
		)
		(pad "41" smd rect
			(at 0.75 -3.749 270)
			(size 0.3 1.55)
			(layers "F.Cu" "F.Paste" "F.Mask")
			(net 61 "PCIE1_RX0_P")
			(pinfunction "PER0_P")
			(pintype "output")
		)
		(pad "42" smd rect
			(at 1 3.749 270)
			(size 0.3 1.55)
			(layers "F.Cu" "F.Paste" "F.Mask")
			(net 226 "unconnected-(J1-VENDOR_3-Pad42)")
			(pinfunction "VENDOR_3")
			(pintype "bidirectional+no_connect")
		)
		(pad "43" smd rect
			(at 1.25 -3.749 270)
			(size 0.3 1.55)
			(layers "F.Cu" "F.Paste" "F.Mask")
			(net 60 "PCIE1_RX0_N")
			(pinfunction "PER0_N")
			(pintype "output")
		)
		(pad "44" smd rect
			(at 1.5 3.749 270)
			(size 0.3 1.55)
			(layers "F.Cu" "F.Paste" "F.Mask")
			(net 227 "unconnected-(J1-COEX3-Pad44)")
			(pinfunction "COEX3")
			(pintype "bidirectional+no_connect")
		)
		(pad "45" smd rect
			(at 1.75 -3.749 270)
			(size 0.3 1.55)
			(layers "F.Cu" "F.Paste" "F.Mask")
			(net 1 "GND")
			(pinfunction "GND")
			(pintype "passive")
		)
		(pad "46" smd rect
			(at 2 3.749 270)
			(size 0.3 1.55)
			(layers "F.Cu" "F.Paste" "F.Mask")
			(net 228 "unconnected-(J1-COEX_TXD-Pad46)")
			(pinfunction "COEX_TXD")
			(pintype "bidirectional+no_connect")
		)
		(pad "47" smd rect
			(at 2.25 -3.749 270)
			(size 0.3 1.55)
			(layers "F.Cu" "F.Paste" "F.Mask")
			(net 63 "PCIE1_CLK_P")
			(pinfunction "REFCLK0_P")
			(pintype "input")
		)
		(pad "48" smd rect
			(at 2.5 3.749 270)
			(size 0.3 1.55)
			(layers "F.Cu" "F.Paste" "F.Mask")
			(net 229 "unconnected-(J1-COEX_RXD-Pad48)")
			(pinfunction "COEX_RXD")
			(pintype "bidirectional+no_connect")
		)
		(pad "49" smd rect
			(at 2.75 -3.749 270)
			(size 0.3 1.55)
			(layers "F.Cu" "F.Paste" "F.Mask")
			(net 62 "PCIE1_CLK_N")
			(pinfunction "REFCLK0_N")
			(pintype "input")
		)
		(pad "50" smd rect
			(at 3 3.749 270)
			(size 0.3 1.55)
			(layers "F.Cu" "F.Paste" "F.Mask")
			(net 216 "/M.2/M2_E_SUSCLK")
			(pinfunction "SUSCLK")
			(pintype "input")
		)
		(pad "51" smd rect
			(at 3.25 -3.749 270)
			(size 0.3 1.55)
			(layers "F.Cu" "F.Paste" "F.Mask")
			(net 1 "GND")
			(pinfunction "GND")
			(pintype "passive")
		)
		(pad "52" smd rect
			(at 3.5 3.749 270)
			(size 0.3 1.55)
			(layers "F.Cu" "F.Paste" "F.Mask")
			(net 65 "PCIE1_RST*")
			(pinfunction "~{PERST0}")
			(pintype "input")
		)
		(pad "53" smd rect
			(at 3.75 -3.749 270)
			(size 0.3 1.55)
			(layers "F.Cu" "F.Paste" "F.Mask")
			(net 64 "PCIE1_CLKREQ*")
			(pinfunction "~{CLKREQ0}")
			(pintype "output")
		)
		(pad "54" smd rect
			(at 4 3.749 270)
			(size 0.3 1.55)
			(layers "F.Cu" "F.Paste" "F.Mask")
			(net 218 "/M.2/M2_E_W_DIS_2")
			(pinfunction "W_DISABLE2")
			(pintype "input")
		)
		(pad "55" smd rect
			(at 4.25 -3.749 270)
			(size 0.3 1.55)
			(layers "F.Cu" "F.Paste" "F.Mask")
			(net 171 "/M.2/PCIE_WAKE_SEL1")
			(pinfunction "~{PEWAKE0}")
			(pintype "output")
		)
		(pad "56" smd rect
			(at 4.5 3.749 270)
			(size 0.3 1.55)
			(layers "F.Cu" "F.Paste" "F.Mask")
			(net 220 "/M.2/M2_E_W_DIS_1")
			(pinfunction "W_DISABLE1")
			(pintype "input")
		)
		(pad "57" smd rect
			(at 4.75 -3.749 270)
			(size 0.3 1.55)
			(layers "F.Cu" "F.Paste" "F.Mask")
			(net 1 "GND")
			(pinfunction "GND")
			(pintype "passive")
		)
		(pad "58" smd rect
			(at 5 3.749 270)
			(size 0.3 1.55)
			(layers "F.Cu" "F.Paste" "F.Mask")
			(net 221 "/M.2/M2_E_I2C_DAT")
			(pinfunction "I2C_DATA")
			(pintype "bidirectional")
		)
		(pad "59" smd rect
			(at 5.25 -3.749 270)
			(size 0.3 1.55)
			(layers "F.Cu" "F.Paste" "F.Mask")
			(net 230 "unconnected-(J1-PET1_P-Pad59)")
			(pinfunction "PET1_P")
			(pintype "input+no_connect")
		)
		(pad "60" smd rect
			(at 5.5 3.749 270)
			(size 0.3 1.55)
			(layers "F.Cu" "F.Paste" "F.Mask")
			(net 223 "/M.2/M2_E_I2C_CLK")
			(pinfunction "I2C_CLK")
			(pintype "bidirectional")
		)
		(pad "61" smd rect
			(at 5.75 -3.749 270)
			(size 0.3 1.55)
			(layers "F.Cu" "F.Paste" "F.Mask")
			(net 231 "unconnected-(J1-PET1_N-Pad61)")
			(pinfunction "PET1_N")
			(pintype "input+no_connect")
		)
		(pad "62" smd rect
			(at 6 3.749 270)
			(size 0.3 1.55)
			(layers "F.Cu" "F.Paste" "F.Mask")
			(net 225 "/M.2/~{M2_E_ALERT}")
			(pinfunction "~{ALERT}")
			(pintype "output")
		)
		(pad "63" smd rect
			(at 6.25 -3.749 270)
			(size 0.3 1.55)
			(layers "F.Cu" "F.Paste" "F.Mask")
			(net 1 "GND")
			(pinfunction "GND")
			(pintype "passive")
		)
		(pad "64" smd rect
			(at 6.5 3.749 270)
			(size 0.3 1.55)
			(layers "F.Cu" "F.Paste" "F.Mask")
			(net 232 "unconnected-(J1-RFU-Pad64)")
			(pinfunction "RFU")
			(pintype "no_connect")
		)
		(pad "65" smd rect
			(at 6.75 -3.749 270)
			(size 0.3 1.55)
			(layers "F.Cu" "F.Paste" "F.Mask")
			(net 233 "unconnected-(J1-PER1_P-Pad65)")
			(pinfunction "PER1_P")
			(pintype "output+no_connect")
		)
		(pad "66" smd rect
			(at 6.999 3.749 270)
			(size 0.3 1.55)
			(layers "F.Cu" "F.Paste" "F.Mask")
			(net 280 "unconnected-(J1-UIM_SWP-Pad66)")
			(pinfunction "UIM_SWP")
			(pintype "bidirectional+no_connect")
		)
		(pad "67" smd rect
			(at 7.249 -3.749 270)
			(size 0.3 1.55)
			(layers "F.Cu" "F.Paste" "F.Mask")
			(net 288 "unconnected-(J1-PER1_N-Pad67)")
			(pinfunction "PER1_N")
			(pintype "output+no_connect")
		)
		(pad "68" smd rect
			(at 7.499 3.749 270)
			(size 0.3 1.55)
			(layers "F.Cu" "F.Paste" "F.Mask")
			(net 289 "unconnected-(J1-UIM_POWER_SNK-Pad68)")
			(pinfunction "UIM_POWER_SNK")
			(pintype "bidirectional+no_connect")
		)
		(pad "69" smd rect
			(at 7.749 -3.749 270)
			(size 0.3 1.55)
			(layers "F.Cu" "F.Paste" "F.Mask")
			(net 1 "GND")
			(pinfunction "GND")
			(pintype "passive")
		)
		(pad "70" smd rect
			(at 7.999 3.749 270)
			(size 0.3 1.55)
			(layers "F.Cu" "F.Paste" "F.Mask")
			(net 290 "unconnected-(J1-UIM_POWER_SRC-Pad70)")
			(pinfunction "UIM_POWER_SRC")
			(pintype "bidirectional+no_connect")
		)
		(pad "71" smd rect
			(at 8.249 -3.749 270)
			(size 0.3 1.55)
			(layers "F.Cu" "F.Paste" "F.Mask")
			(net 291 "unconnected-(J1-REFCLK1_P-Pad71)")
			(pinfunction "REFCLK1_P")
			(pintype "input+no_connect")
		)
		(pad "72" smd rect
			(at 8.499 3.749 270)
			(size 0.3 1.55)
			(layers "F.Cu" "F.Paste" "F.Mask")
			(net 87 "+3V3")
			(pinfunction "3.3V")
			(pintype "passive")
		)
		(pad "73" smd rect
			(at 8.749 -3.749 270)
			(size 0.3 1.55)
			(layers "F.Cu" "F.Paste" "F.Mask")
			(net 292 "unconnected-(J1-REFCLK1_N-Pad73)")
			(pinfunction "REFCLK1_N")
			(pintype "input+no_connect")
		)
		(pad "74" smd rect
			(at 8.999 3.749 270)
			(size 0.3 1.55)
			(layers "F.Cu" "F.Paste" "F.Mask")
			(net 87 "+3V3")
			(pinfunction "3.3V")
			(pintype "passive")
		)
		(pad "75" smd rect
			(at 9.249 -3.749 270)
			(size 0.3 1.55)
			(layers "F.Cu" "F.Paste" "F.Mask")
			(net 1 "GND")
			(pinfunction "GND")
			(pintype "passive")
		)
		(pad "MP" smd rect
			(at -10.35 -3.001 270)
			(size 1.2 2.75)
			(layers "F.Cu" "F.Paste" "F.Mask")
			(net 1 "GND")
			(pinfunction "MP")
			(pintype "passive")
		)
		(pad "MP" smd rect
			(at 10.351 -3.001 270)
			(size 1.2 2.75)
			(layers "F.Cu" "F.Paste" "F.Mask")
			(net 1 "GND")
			(pinfunction "MP")
			(pintype "passive")
		)
	)
)
